# S9S_MB_2U (Grand Teton) — schematic netlist excerpt (pin names and nets, part order shuffled) for the footprints in the layout excerpt that follows; sources: Cadence DE-HDL packaged netlist, KiCad conversion of 03242023_DA0F0TMBIJ0_F0T_Motherboard_J_brd_V01_OCP.brd

PC1674  Q_CAP  22UF 16V 20% X6S  pkg C0805  page 272 : A = SW_P12V_PVCCFA_EHV_FIVRA_CPU0_R ; B = GND

Q72  MOSFET_NCH_DUAL  PJT138K IC  pkg SOT363XD  page 148
  S1  = GND
  G1  = FM_GPU_PWRGD
  D2  = FM_GPU_PWRGD_ISO
  S2  = GND
  G2  = FM_GPU_PWRGD_N
  D1  = FM_GPU_PWRGD_N

R629  Q_RES  1K 1% CHIP  pkg 0402LF  page 127 : A = P3V3_AUX ; B = PU_PIROM_CPU1_ADDR0

(kicad_pcb
	(version 20260206)
	(generator "pcbnew")
	(generator_version "10.0")
	(general
		(thickness 1.6)
		(legacy_teardrops no)
	)
	(paper "A4")
	(title_block
		(title "03242023_DA0F0TMBIJ0_F0T_Motherboard_J_brd_V01_OCP.brd")
		(comment 1 "Grand Teton / footprints 3470-3472 of 6105")
	)
	(layers
		(0 "F.Cu" signal "TOP")
		(4 "In1.Cu" signal "GND")
		(6 "In2.Cu" signal "IN1")
		(8 "In3.Cu" signal "GND1")
		(10 "In4.Cu" signal "IN2")
		(12 "In5.Cu" signal "GND2")
		(14 "In6.Cu" signal "IN3")
		(16 "In7.Cu" signal "GND3")
		(18 "In8.Cu" signal "VCC")
		(20 "In9.Cu" signal "VCC1")
		(22 "In10.Cu" signal "GND4")
		(24 "In11.Cu" signal "IN4")
		(26 "In12.Cu" signal "GND5")
		(28 "In13.Cu" signal "IN5")
		(30 "In14.Cu" signal "GND6")
		(32 "In15.Cu" signal "IN6")
		(34 "In16.Cu" signal "GND7")
		(2 "B.Cu" signal "BOTTOM")
		(9 "F.Adhes" user "F.Adhesive")
		(11 "B.Adhes" user "B.Adhesive")
		(13 "F.Paste" user "Package Geometry/Pastemask Top")
		(15 "B.Paste" user "Package Geometry/Pastemask Bottom")
		(5 "F.SilkS" user "Ref Des/Silkscreen Top")
		(7 "B.SilkS" user "Ref Des/Silkscreen Bottom")
		(1 "F.Mask" user "Board Geometry/Soldermask Top")
		(3 "B.Mask" user "Board Geometry/Soldermask Bottom")
		(17 "Dwgs.User" user "User.Drawings")
		(19 "Cmts.User" user "User.Comments")
		(21 "Eco1.User" user "User.Eco1")
		(23 "Eco2.User" user "User.Eco2")
		(25 "Edge.Cuts" user "Board Geometry/Outline")
		(27 "Margin" user)
		(31 "F.CrtYd" user "Package Geometry/Place Bound Top")
		(29 "B.CrtYd" user "Package Geometry/Place Bound Bottom")
		(35 "F.Fab" user "Ref Des/Assembly Top")
		(33 "B.Fab" user "Ref Des/Assembly Bottom")
	)
	(footprint ""
		(layer "F.Cu")
		(at 193.93408 -354.904548 180)
		(property "Reference" "R629"
			(at 0 0 180)
			(layer "F.SilkS")
			(hide yes)
			(effects
				(font
					(size 1.27 1.27)
				)
			)
		)
		(property "Value" ""
			(at 0 0 180)
			(layer "F.Fab")
			(effects
				(font
					(size 1.27 1.27)
				)
			)
		)
		(duplicate_pad_numbers_are_jumpers no)
		(fp_line
			(start 0.7874 0.4064)
			(end -0.7874 0.4064)
			(stroke
				(width 0.1524)
				(type default)
			)
			(layer "F.SilkS")
		)
		(fp_line
			(start 0.7874 -0.4064)
			(end 0.7874 0.4064)
			(stroke
				(width 0.1524)
				(type default)
			)
			(layer "F.SilkS")
		)
		(fp_line
			(start -0.7874 0.4064)
			(end -0.7874 -0.4064)
			(stroke
				(width 0.1524)
				(type default)
			)
			(layer "F.SilkS")
		)
		(fp_line
			(start -0.7874 -0.4064)
			(end 0.7874 -0.4064)
			(stroke
				(width 0.1524)
				(type default)
			)
			(layer "F.SilkS")
		)
		(fp_line
			(start 0.67945 0.3048)
			(end 0.120396 0.3048)
			(stroke
				(width 0.1)
				(type default)
			)
			(layer "F.Fab")
		)
		(fp_line
			(start 0.67945 -0.3048)
			(end 0.67945 0.3048)
			(stroke
				(width 0.1)
				(type default)
			)
			(layer "F.Fab")
		)
		(fp_line
			(start 0.12065 -0.2794)
			(end 0.12065 -0.3048)
			(stroke
				(width 0.1)
				(type default)
			)
			(layer "F.Fab")
		)
		(fp_line
			(start 0.12065 -0.3048)
			(end 0.67945 -0.3048)
			(stroke
				(width 0.1)
				(type default)
			)
			(layer "F.Fab")
		)
		(fp_line
			(start 0.120396 0.3048)
			(end 0.120396 0.2794)
			(stroke
				(width 0.1)
				(type default)
			)
			(layer "F.Fab")
		)
		(fp_line
			(start 0.120396 0.2794)
			(end -0.12065 0.2794)
			(stroke
				(width 0.1)
				(type default)
			)
			(layer "F.Fab")
		)
		(fp_line
			(start -0.12065 0.3048)
			(end -0.67945 0.3048)
			(stroke
				(width 0.1)
				(type default)
			)
			(layer "F.Fab")
		)
		(fp_line
			(start -0.12065 0.2794)
			(end -0.12065 0.3048)
			(stroke
				(width 0.1)
				(type default)
			)
			(layer "F.Fab")
		)
		(fp_line
			(start -0.12065 -0.2794)
			(end 0.12065 -0.2794)
			(stroke
				(width 0.1)
				(type default)
			)
			(layer "F.Fab")
		)
		(fp_line
			(start -0.12065 -0.305054)
			(end -0.12065 -0.2794)
			(stroke
				(width 0.1)
				(type default)
			)
			(layer "F.Fab")
		)
		(fp_line
			(start -0.67945 0.3048)
			(end -0.67945 -0.305054)
			(stroke
				(width 0.1)
				(type default)
			)
			(layer "F.Fab")
		)
		(fp_line
			(start -0.67945 -0.305054)
			(end -0.12065 -0.305054)
			(stroke
				(width 0.1)
				(type default)
			)
			(layer "F.Fab")
		)
		(pad "1" smd circle
			(at -0.40005 0 180)
			(size 0 0)
			(layers "F.Cu" "F.Mask" "F.Paste")
			(net "P3V3_AUX")
		)
		(pad "2" smd circle
			(at 0.40005 0 180)
			(size 0 0)
			(layers "F.Cu" "F.Mask" "F.Paste")
			(net "PU_PIROM_CPU1_ADDR0")
		)
	)
	(footprint ""
		(layer "F.Cu")
		(at 431.433478 -364.574328)
		(property "Reference" "PC1674"
			(at 0 0 0)
			(layer "F.SilkS")
			(hide yes)
			(effects
				(font
					(size 1.27 1.27)
				)
			)
		)
		(property "Value" ""
			(at 0 0 0)
			(layer "F.Fab")
			(effects
				(font
					(size 1.27 1.27)
				)
			)
		)
		(duplicate_pad_numbers_are_jumpers no)
		(fp_line
			(start -1.524 -0.762)
			(end 1.524 -0.762)
			(stroke
				(width 0.1524)
				(type default)
			)
			(layer "F.SilkS")
		)
		(fp_line
			(start -1.524 0.762)
			(end -1.524 -0.762)
			(stroke
				(width 0.1524)
				(type default)
			)
			(layer "F.SilkS")
		)
		(fp_line
			(start 1.524 -0.762)
			(end 1.524 0.762)
			(stroke
				(width 0.1524)
				(type default)
			)
			(layer "F.SilkS")
		)
		(fp_line
			(start 1.524 0.762)
			(end -1.524 0.762)
			(stroke
				(width 0.1524)
				(type default)
			)
			(layer "F.SilkS")
		)
		(fp_line
			(start -1.1049 -0.724916)
			(end -1.1049 0.724916)
			(stroke
				(width 0.1)
				(type default)
			)
			(layer "F.Fab")
		)
		(fp_line
			(start -1.1049 0.724916)
			(end 1.1049 0.724916)
			(stroke
				(width 0.1)
				(type default)
			)
			(layer "F.Fab")
		)
		(fp_line
			(start 1.1049 -0.724916)
			(end -1.1049 -0.724916)
			(stroke
				(width 0.1)
				(type default)
			)
			(layer "F.Fab")
		)
		(fp_line
			(start 1.1049 0.724916)
			(end 1.1049 -0.724916)
			(stroke
				(width 0.1)
				(type default)
			)
			(layer "F.Fab")
		)
		(pad "1" smd rect
			(at -0.889 0 180)
			(size 1.016 1.27)
			(layers "F.Cu" "F.Mask" "F.Paste")
			(net "SW_P12V_PVCCFA_EHV_FIVRA_CPU0_R")
		)
		(pad "2" smd rect
			(at 0.889 0 180)
			(size 1.016 1.27)
			(layers "F.Cu" "F.Mask" "F.Paste")
			(net "GND")
		)
	)
	(footprint ""
		(layer "F.Cu")
		(at 28.081732 -416.016948)
		(property "Reference" "Q72"
			(at 0.2286 -1.918208 0)
			(unlocked yes)
			(layer "F.SilkS")
			(effects
				(font
					(size 0.7874 0.5842)
					(thickness 0.1524)
				)
				(justify left)
			)
		)
		(property "Value" ""
			(at 0 0 0)
			(layer "F.Fab")
			(effects
				(font
					(size 1.27 1.27)
				)
			)
		)
		(duplicate_pad_numbers_are_jumpers no)
		(fp_line
			(start -1.332738 -1.100074)
			(end -0.4826 -1.100074)
			(stroke
				(width 0.1524)
				(type default)
			)
			(layer "F.SilkS")
		)
		(fp_line
			(start -1.332738 1.100074)
			(end -1.332738 -1.100074)
			(stroke
				(width 0.1524)
				(type default)
			)
			(layer "F.SilkS")
		)
		(fp_line
			(start -0.4826 -1.100074)
			(end 0 -0.541274)
			(stroke
				(width 0.1524)
				(type default)
			)
			(layer "F.SilkS")
		)
		(fp_line
			(start 0 -0.541274)
			(end 0.4826 -1.100074)
			(stroke
				(width 0.1524)
				(type default)
			)
			(layer "F.SilkS")
		)
		(fp_line
			(start 0.4826 -1.100074)
			(end 1.332738 -1.100074)
			(stroke
				(width 0.1524)
				(type default)
			)
			(layer "F.SilkS")
		)
		(fp_line
			(start 1.332738 -1.100074)
			(end 1.332738 1.100074)
			(stroke
				(width 0.1524)
				(type default)
			)
			(layer "F.SilkS")
		)
		(fp_line
			(start 1.332738 1.100074)
			(end -1.332738 1.100074)
			(stroke
				(width 0.1524)
				(type default)
			)
			(layer "F.SilkS")
		)
		(fp_poly
			(pts
				(xy -0.94996 -1.23317) (xy -1.300988 -1.935226) (xy -0.598932 -1.935226)
			)
			(stroke
				(width 0)
				(type default)
			)
			(fill yes)
			(layer "F.SilkS")
		)
		(fp_line
			(start -0.674878 -1.100074)
			(end 0.674878 -1.100074)
			(stroke
				(width 0.1)
				(type default)
			)
			(layer "F.Fab")
		)
		(fp_line
			(start -0.674878 1.100074)
			(end -0.674878 -1.100074)
			(stroke
				(width 0.1)
				(type default)
			)
			(layer "F.Fab")
		)
		(fp_line
			(start 0.674878 -1.100074)
			(end 0.674878 1.100074)
			(stroke
				(width 0.1)
				(type default)
			)
			(layer "F.Fab")
		)
		(fp_line
			(start 0.674878 1.100074)
			(end -0.674878 1.100074)
			(stroke
				(width 0.1)
				(type default)
			)
			(layer "F.Fab")
		)
		(fp_poly
			(pts
				(xy -2.2352 -0.298958) (xy -2.2352 -1.001014) (xy -1.533144 -0.649986)
			)
			(stroke
				(width 0)
				(type default)
			)
			(fill yes)
			(layer "F.Fab")
		)
		(pad "1" smd rect
			(at -0.94996 -0.649986 90)
			(size 0.4318 0.508)
			(layers "F.Cu" "F.Mask" "F.Paste")
			(net "GND")
		)
		(pad "2" smd rect
			(at -0.94996 0 90)
			(size 0.4318 0.508)
			(layers "F.Cu" "F.Mask" "F.Paste")
			(net "FM_GPU_PWRGD")
		)
		(pad "3" smd rect
			(at -0.94996 0.649986 90)
			(size 0.4318 0.508)
			(layers "F.Cu" "F.Mask" "F.Paste")
			(net "FM_GPU_PWRGD_ISO")
		)
		(pad "4" smd rect
			(at 0.94996 0.649986 90)
			(size 0.4318 0.508)
			(layers "F.Cu" "F.Mask" "F.Paste")
			(net "GND")
		)
		(pad "5" smd rect
			(at 0.94996 0 90)
			(size 0.4318 0.508)
			(layers "F.Cu" "F.Mask" "F.Paste")
			(net "FM_GPU_PWRGD_N")
		)
		(pad "6" smd rect
			(at 0.94996 -0.649986 90)
			(size 0.4318 0.508)
			(layers "F.Cu" "F.Mask" "F.Paste")
			(net "FM_GPU_PWRGD_N")
		)
	)
)
